(kicad_pcb
	(version 20241229)
	(generator "pcbnew")
	(generator_version "9.0")
	(general
		(thickness 1.63)
		(legacy_teardrops no)
	)
	(paper "A4")
	(title_block
		(title "CM4 Baseboard")
		(date "2026-01-05")
		(rev "1.1.1")
		(company "Antmicro Ltd")
		(comment 1 "www.antmicro.com")
		(comment 9 "footprints 138-142 of 506")
	)
	(layers
		(0 "F.Cu" signal)
		(4 "In1.Cu" power)
		(6 "In2.Cu" power)
		(8 "In3.Cu" signal)
		(10 "In4.Cu" signal)
		(2 "B.Cu" signal)
		(9 "F.Adhes" user "F.Adhesive")
		(11 "B.Adhes" user "B.Adhesive")
		(13 "F.Paste" user)
		(15 "B.Paste" user)
		(5 "F.SilkS" user "F.Silkscreen")
		(7 "B.SilkS" user "B.Silkscreen")
		(1 "F.Mask" user)
		(3 "B.Mask" user)
		(17 "Dwgs.User" user "User.Drawings")
		(19 "Cmts.User" user "User.Comments")
		(21 "Eco1.User" user "User.Eco1")
		(23 "Eco2.User" user "User.Eco2")
		(25 "Edge.Cuts" user)
		(27 "Margin" user)
		(31 "F.CrtYd" user "F.Courtyard")
		(29 "B.CrtYd" user "B.Courtyard")
		(35 "F.Fab" user)
		(33 "B.Fab" user)
	)
	(footprint "antmicro-footprints:C_0402_1005Metric"
		(layer "F.Cu")
		(at 61.117962 175.7255 -90)
		(descr "Capacitor SMD 0402")
		(tags "capacitor SMD 0402")
		(property "Reference" "C827"
			(at -3.579 14.88 90)
			(layer "F.SilkS")
			(effects
				(font
					(size 0.7 0.7)
					(thickness 0.15)
				)
				(justify right bottom)
			)
		)
		(property "Value" "C_template_name_0402"
			(at -1.022927 2.155213 90)
			(layer "F.Fab")
			(effects
				(font
					(size 0.7 0.7)
					(thickness 0.15)
				)
				(justify right bottom)
			)
		)
		(property "Datasheet" "template_datasheet"
			(at 0 0 270)
			(layer "F.Fab")
			(hide yes)
			(effects
				(font
					(size 1.27 1.27)
					(thickness 0.15)
				)
			)
		)
		(property "MPN" "template_MPN"
			(at 0 0 270)
			(unlocked yes)
			(layer "F.Fab")
			(hide yes)
			(effects
				(font
					(size 1 1)
					(thickness 0.15)
				)
			)
		)
		(property "Manufacturer" "template_manufacturer"
			(at 0 0 270)
			(unlocked yes)
			(layer "F.Fab")
			(hide yes)
			(effects
				(font
					(size 1 1)
					(thickness 0.15)
				)
			)
		)
		(property "License" "Apache-2.0"
			(at 0 0 270)
			(unlocked yes)
			(layer "F.Fab")
			(hide yes)
			(effects
				(font
					(size 1 1)
					(thickness 0.15)
				)
			)
		)
		(property "Author" "Antmicro"
			(at 0 0 270)
			(unlocked yes)
			(layer "F.Fab")
			(hide yes)
			(effects
				(font
					(size 1 1)
					(thickness 0.15)
				)
			)
		)
		(property "Val" "template_value"
			(at 0 0 270)
			(unlocked yes)
			(layer "F.Fab")
			(hide yes)
			(effects
				(font
					(size 1 1)
					(thickness 0.15)
				)
			)
		)
		(property "Voltage" "template_voltage"
			(at 0 0 270)
			(unlocked yes)
			(layer "F.Fab")
			(hide yes)
			(effects
				(font
					(size 1 1)
					(thickness 0.15)
				)
			)
		)
		(property "Dielectric" "template_dielectric"
			(at 0 0 270)
			(unlocked yes)
			(layer "F.Fab")
			(hide yes)
			(effects
				(font
					(size 1 1)
					(thickness 0.15)
				)
			)
		)
		(sheetname "/Peripherals/")
		(sheetfile "peripherals.kicad_sch")
		(attr smd exclude_from_pos_files exclude_from_bom dnp)
		(fp_rect
			(start -0.925 -0.47)
			(end 0.925 0.47)
			(stroke
				(width 0.05)
				(type default)
			)
			(fill no)
			(layer "F.CrtYd")
		)
		(fp_line
			(start -0.494 0.248)
			(end -0.494 -0.25)
			(stroke
				(width 0.15)
				(type solid)
			)
			(layer "F.Fab")
		)
		(fp_line
			(start 0.504 0.248)
			(end -0.494 0.248)
			(stroke
				(width 0.15)
				(type solid)
			)
			(layer "F.Fab")
		)
		(fp_line
			(start -0.494 -0.25)
			(end 0.504 -0.25)
			(stroke
				(width 0.15)
				(type solid)
			)
			(layer "F.Fab")
		)
		(fp_line
			(start 0.504 -0.25)
			(end 0.504 0.248)
			(stroke
				(width 0.15)
				(type solid)
			)
			(layer "F.Fab")
		)
		(fp_text user "${REFERENCE}"
			(at -0.939 4.599 270)
			(layer "F.Fab")
			(effects
				(font
					(size 0.7 0.7)
					(thickness 0.15)
				)
				(justify left bottom)
			)
		)
		(fp_text user "Author: Antmicro"
			(at -0.939 3.399 270)
			(layer "F.Fab")
			(effects
				(font
					(size 0.7 0.7)
					(thickness 0.15)
				)
				(justify left bottom)
			)
		)
		(fp_text user "License: Apache-2.0"
			(at -0.939 5.799 270)
			(layer "F.Fab")
			(effects
				(font
					(size 0.7 0.7)
					(thickness 0.15)
				)
				(justify left bottom)
			)
		)
		(pad "1" smd roundrect
			(at -0.48 0 270)
			(size 0.59 0.64)
			(layers "F.Cu" "F.Mask" "F.Paste")
			(roundrect_rratio 0.25)
			(net 106 "Net-(C814-Pad2)")
			(pintype "passive")
		)
		(pad "2" smd roundrect
			(at 0.48 0 270)
			(size 0.59 0.64)
			(layers "F.Cu" "F.Mask" "F.Paste")
			(roundrect_rratio 0.25)
			(net 3 "GND")
			(pintype "passive")
		)
	)
	(footprint "antmicro-footprints:R_0402_1005Metric"
		(layer "F.Cu")
		(at 100.767962 119.079 90)
		(descr "Resistor SMD 0402")
		(tags "resistor SMD 0402")
		(property "Reference" "R915"
			(at -26.5325 27.945 90)
			(layer "F.SilkS")
			(effects
				(font
					(size 0.7 0.7)
					(thickness 0.15)
				)
				(justify left bottom)
			)
		)
		(property "Value" "R_470k_0402"
			(at -1.011843 1.772047 90)
			(layer "F.Fab")
			(effects
				(font
					(size 0.7 0.7)
					(thickness 0.15)
				)
				(justify left bottom)
			)
		)
		(property "Datasheet" "https://www.bourns.com/docs/product-datasheets/cr.pdf"
			(at 0 0 90)
			(layer "F.Fab")
			(hide yes)
			(effects
				(font
					(size 1.27 1.27)
					(thickness 0.15)
				)
			)
		)
		(property "MPN" "CR0402-FX-4703GLF"
			(at 0 0 90)
			(unlocked yes)
			(layer "F.Fab")
			(hide yes)
			(effects
				(font
					(size 1 1)
					(thickness 0.15)
				)
			)
		)
		(property "Manufacturer" "Bourns"
			(at 0 0 90)
			(unlocked yes)
			(layer "F.Fab")
			(hide yes)
			(effects
				(font
					(size 1 1)
					(thickness 0.15)
				)
			)
		)
		(property "License" "Apache-2.0"
			(at 0 0 90)
			(unlocked yes)
			(layer "F.Fab")
			(hide yes)
			(effects
				(font
					(size 1 1)
					(thickness 0.15)
				)
			)
		)
		(property "Author" "Antmicro"
			(at 0 0 90)
			(unlocked yes)
			(layer "F.Fab")
			(hide yes)
			(effects
				(font
					(size 1 1)
					(thickness 0.15)
				)
			)
		)
		(property "Val" "470k"
			(at 0 0 90)
			(unlocked yes)
			(layer "F.Fab")
			(hide yes)
			(effects
				(font
					(size 1 1)
					(thickness 0.15)
				)
			)
		)
		(property "Tolerance" "1%"
			(at 0 0 90)
			(unlocked yes)
			(layer "F.Fab")
			(hide yes)
			(effects
				(font
					(size 1 1)
					(thickness 0.15)
				)
			)
		)
		(sheetname "/USB/")
		(sheetfile "usb.kicad_sch")
		(attr smd)
		(fp_rect
			(start -0.925 -0.47)
			(end 0.925 0.47)
			(stroke
				(width 0.05)
				(type default)
			)
			(fill no)
			(layer "F.CrtYd")
		)
		(fp_rect
			(start -0.5 -0.25)
			(end 0.5 0.25)
			(stroke
				(width 0.15)
				(type solid)
			)
			(fill no)
			(layer "F.Fab")
		)
		(fp_text user "${REFERENCE}"
			(at -0.95 3.168 90)
			(layer "F.Fab")
			(effects
				(font
					(size 0.7 0.7)
					(thickness 0.15)
				)
				(justify left bottom)
			)
		)
		(fp_text user "Author: Antmicro"
			(at -0.95 4.169 90)
			(layer "F.Fab")
			(effects
				(font
					(size 0.7 0.7)
					(thickness 0.15)
				)
				(justify left bottom)
			)
		)
		(fp_text user "License: Apache-2.0"
			(at -0.95 5.169 90)
			(layer "F.Fab")
			(effects
				(font
					(size 0.7 0.7)
					(thickness 0.15)
				)
				(justify left bottom)
			)
		)
		(pad "1" smd roundrect
			(at -0.48 0 90)
			(size 0.59 0.64)
			(layers "F.Cu" "F.Mask" "F.Paste")
			(roundrect_rratio 0.25)
			(net 432 "Net-(U906-CURRENT_MODE)")
			(pintype "passive")
		)
		(pad "2" smd roundrect
			(at 0.48 0 90)
			(size 0.59 0.64)
			(layers "F.Cu" "F.Mask" "F.Paste")
			(roundrect_rratio 0.25)
			(net 28 "/USB/+5V_{CAP}")
			(pintype "passive")
		)
	)
	(footprint "antmicro-footprints:Nexperia_DFN-10_2.5x1mm_P0.5mm"
		(layer "F.Cu")
		(at 132.342962 118.9415)
		(property "Reference" "D806"
			(at 1.415 0.355 0)
			(layer "F.SilkS")
			(effects
				(font
					(size 0.7 0.7)
					(thickness 0.15)
				)
				(justify left bottom)
			)
		)
		(property "Value" "PUSB3F96X_PASS"
			(at -0.016 1.705 0)
			(layer "F.Fab")
			(effects
				(font
					(size 0.7 0.7)
					(thickness 0.15)
				)
				(justify left bottom)
			)
		)
		(property "Datasheet" "https://mouser.com/datasheet/2/916/PUSB3F96-1600324.pdf"
			(at 0 0 0)
			(layer "F.Fab")
			(hide yes)
			(effects
				(font
					(size 1.27 1.27)
					(thickness 0.15)
				)
			)
		)
		(property "Manufacturer" "Nexperia"
			(at 0 0 0)
			(unlocked yes)
			(layer "F.Fab")
			(hide yes)
			(effects
				(font
					(size 1 1)
					(thickness 0.15)
				)
			)
		)
		(property "MPN" "PUSB3F96X"
			(at 0 0 0)
			(unlocked yes)
			(layer "F.Fab")
			(hide yes)
			(effects
				(font
					(size 1 1)
					(thickness 0.15)
				)
			)
		)
		(property "Author" "Antmicro"
			(at 0 0 0)
			(unlocked yes)
			(layer "F.Fab")
			(hide yes)
			(effects
				(font
					(size 1 1)
					(thickness 0.15)
				)
			)
		)
		(property "License" "Apache-2.0"
			(at 0 0 0)
			(unlocked yes)
			(layer "F.Fab")
			(hide yes)
			(effects
				(font
					(size 1 1)
					(thickness 0.15)
				)
			)
		)
		(sheetname "/Peripherals/")
		(sheetfile "peripherals.kicad_sch")
		(attr smd)
		(fp_line
			(start -1.375 -0.4)
			(end -1.375 0.4)
			(stroke
				(width 0.15)
				(type solid)
			)
			(layer "F.SilkS")
		)
		(fp_line
			(start 1.375 0.4)
			(end 1.375 -0.4)
			(stroke
				(width 0.15)
				(type solid)
			)
			(layer "F.SilkS")
		)
		(fp_circle
			(center -1.4 0.7)
			(end -1.349 0.7)
			(stroke
				(width 0.15)
				(type solid)
			)
			(fill yes)
			(layer "F.SilkS")
		)
		(fp_rect
			(start -1.4 -0.725)
			(end 1.4 0.725)
			(stroke
				(width 0.05)
				(type solid)
			)
			(fill no)
			(layer "F.CrtYd")
		)
		(fp_line
			(start -1.25 -0.5)
			(end -1.25 0.15)
			(stroke
				(width 0.15)
				(type solid)
			)
			(layer "F.Fab")
		)
		(fp_line
			(start -1.25 0.15)
			(end -0.9 0.5)
			(stroke
				(width 0.15)
				(type solid)
			)
			(layer "F.Fab")
		)
		(fp_line
			(start -0.9 0.5)
			(end 1.25 0.5)
			(stroke
				(width 0.15)
				(type solid)
			)
			(layer "F.Fab")
		)
		(fp_line
			(start 1.25 -0.5)
			(end -1.25 -0.5)
			(stroke
				(width 0.15)
				(type solid)
			)
			(layer "F.Fab")
		)
		(fp_line
			(start 1.25 0.5)
			(end 1.25 -0.5)
			(stroke
				(width 0.15)
				(type solid)
			)
			(layer "F.Fab")
		)
		(fp_text user "${REFERENCE}"
			(at -1.367 3.704 0)
			(layer "F.Fab")
			(effects
				(font
					(size 0.7 0.7)
					(thickness 0.15)
				)
				(justify left bottom)
			)
		)
		(fp_text user "License: Apache-2.0"
			(at -1.367 6.105 0)
			(layer "F.Fab")
			(effects
				(font
					(size 0.7 0.7)
					(thickness 0.15)
				)
				(justify left bottom)
			)
		)
		(fp_text user "Author: Antmicro"
			(at -1.367 4.905 0)
			(layer "F.Fab")
			(effects
				(font
					(size 0.7 0.7)
					(thickness 0.15)
				)
				(justify left bottom)
			)
		)
		(pad "1" smd rect
			(at -1 0.3875)
			(size 0.2 0.475)
			(layers "F.Cu" "F.Mask" "F.Paste")
			(net 142 "/CSI/I_{2}C1.SCL")
			(pinfunction "CH1")
			(pintype "passive")
			(solder_mask_margin 0.05)
		)
		(pad "2" smd rect
			(at -0.5 0.3875)
			(size 0.2 0.475)
			(layers "F.Cu" "F.Mask" "F.Paste")
			(net 143 "/CSI/I_{2}C1.SDA")
			(pinfunction "CH2")
			(pintype "passive")
			(solder_mask_margin 0.05)
		)
		(pad "3" smd rect
			(at 0 0.3875)
			(size 0.2 0.475)
			(layers "F.Cu" "F.Mask" "F.Paste")
			(net 3 "GND")
			(pinfunction "GND")
			(pintype "passive")
			(solder_mask_margin 0.05)
		)
		(pad "4" smd rect
			(at 0.5 0.3875)
			(size 0.2 0.475)
			(layers "F.Cu" "F.Mask" "F.Paste")
			(net 317 "/Peripherals/VLED")
			(pinfunction "CH3")
			(pintype "passive")
			(solder_mask_margin 0.05)
		)
		(pad "5" smd rect
			(at 1 0.3875)
			(size 0.2 0.475)
			(layers "F.Cu" "F.Mask" "F.Paste")
			(net 3 "GND")
			(pinfunction "CH4")
			(pintype "passive")
			(solder_mask_margin 0.05)
		)
		(pad "6" smd rect
			(at 1 -0.3875)
			(size 0.2 0.475)
			(layers "F.Cu" "F.Mask" "F.Paste")
			(net 3 "GND")
			(pinfunction "CH4")
			(pintype "passive")
			(solder_mask_margin 0.05)
		)
		(pad "7" smd rect
			(at 0.5 -0.3875)
			(size 0.2 0.475)
			(layers "F.Cu" "F.Mask" "F.Paste")
			(net 317 "/Peripherals/VLED")
			(pinfunction "CH3")
			(pintype "passive")
			(solder_mask_margin 0.05)
		)
		(pad "8" smd rect
			(at 0 -0.3875)
			(size 0.2 0.475)
			(layers "F.Cu" "F.Mask" "F.Paste")
			(net 3 "GND")
			(pinfunction "GND")
			(pintype "passive")
			(solder_mask_margin 0.05)
		)
		(pad "9" smd rect
			(at -0.501 -0.3875)
			(size 0.2 0.475)
			(layers "F.Cu" "F.Mask" "F.Paste")
			(net 143 "/CSI/I_{2}C1.SDA")
			(pinfunction "CH2")
			(pintype "passive")
			(solder_mask_margin 0.05)
		)
		(pad "10" smd rect
			(at -1 -0.3875)
			(size 0.2 0.475)
			(layers "F.Cu" "F.Mask" "F.Paste")
			(net 142 "/CSI/I_{2}C1.SCL")
			(pinfunction "CH1")
			(pintype "passive")
			(solder_mask_margin 0.05)
		)
	)
	(footprint "antmicro-footprints:C_0402_1005Metric"
		(layer "F.Cu")
		(at 91.867962 132.432236 90)
		(descr "Capacitor SMD 0402")
		(tags "capacitor SMD 0402")
		(property "Reference" "C919"
			(at 0.820736 0.46 90)
			(layer "F.SilkS")
			(effects
				(font
					(size 0.7 0.7)
					(thickness 0.15)
				)
				(justify left bottom)
			)
		)
		(property "Value" "C_100n_0402"
			(at -1.022927 2.155213 90)
			(layer "F.Fab")
			(effects
				(font
					(size 0.7 0.7)
					(thickness 0.15)
				)
				(justify left bottom)
			)
		)
		(property "Datasheet" "https://www.murata.com/products/productdetail?partno=GRM155R61H104KE14%23"
			(at 0 0 90)
			(layer "F.Fab")
			(hide yes)
			(effects
				(font
					(size 1.27 1.27)
					(thickness 0.15)
				)
			)
		)
		(property "Manufacturer" "Murata"
			(at 0 0 90)
			(unlocked yes)
			(layer "F.Fab")
			(hide yes)
			(effects
				(font
					(size 1 1)
					(thickness 0.15)
				)
			)
		)
		(property "MPN" "GRM155R61H104KE14D"
			(at 0 0 90)
			(unlocked yes)
			(layer "F.Fab")
			(hide yes)
			(effects
				(font
					(size 1 1)
					(thickness 0.15)
				)
			)
		)
		(property "Val" "100n"
			(at 0 0 90)
			(unlocked yes)
			(layer "F.Fab")
			(hide yes)
			(effects
				(font
					(size 1 1)
					(thickness 0.15)
				)
			)
		)
		(property "License" "Apache-2.0"
			(at 0 0 90)
			(unlocked yes)
			(layer "F.Fab")
			(hide yes)
			(effects
				(font
					(size 1 1)
					(thickness 0.15)
				)
			)
		)
		(property "Author" "Antmicro"
			(at 0 0 90)
			(unlocked yes)
			(layer "F.Fab")
			(hide yes)
			(effects
				(font
					(size 1 1)
					(thickness 0.15)
				)
			)
		)
		(property "Voltage" "50V"
			(at 0 0 90)
			(unlocked yes)
			(layer "F.Fab")
			(hide yes)
			(effects
				(font
					(size 1 1)
					(thickness 0.15)
				)
			)
		)
		(property "Dielectric" "X5R"
			(at 0 0 90)
			(unlocked yes)
			(layer "F.Fab")
			(hide yes)
			(effects
				(font
					(size 1 1)
					(thickness 0.15)
				)
			)
		)
		(sheetname "/USB/")
		(sheetfile "usb.kicad_sch")
		(attr smd)
		(fp_rect
			(start -0.925 -0.47)
			(end 0.925 0.47)
			(stroke
				(width 0.05)
				(type default)
			)
			(fill no)
			(layer "F.CrtYd")
		)
		(fp_line
			(start 0.504 -0.25)
			(end 0.504 0.248)
			(stroke
				(width 0.15)
				(type solid)
			)
			(layer "F.Fab")
		)
		(fp_line
			(start -0.494 -0.25)
			(end 0.504 -0.25)
			(stroke
				(width 0.15)
				(type solid)
			)
			(layer "F.Fab")
		)
		(fp_line
			(start 0.504 0.248)
			(end -0.494 0.248)
			(stroke
				(width 0.15)
				(type solid)
			)
			(layer "F.Fab")
		)
		(fp_line
			(start -0.494 0.248)
			(end -0.494 -0.25)
			(stroke
				(width 0.15)
				(type solid)
			)
			(layer "F.Fab")
		)
		(fp_text user "License: Apache-2.0"
			(at -0.939 5.799 90)
			(layer "F.Fab")
			(effects
				(font
					(size 0.7 0.7)
					(thickness 0.15)
				)
				(justify left bottom)
			)
		)
		(fp_text user "${REFERENCE}"
			(at -0.939 4.599 90)
			(layer "F.Fab")
			(effects
				(font
					(size 0.7 0.7)
					(thickness 0.15)
				)
				(justify left bottom)
			)
		)
		(fp_text user "Author: Antmicro"
			(at -0.939 3.399 90)
			(layer "F.Fab")
			(effects
				(font
					(size 0.7 0.7)
					(thickness 0.15)
				)
				(justify left bottom)
			)
		)
		(pad "1" smd roundrect
			(at -0.48 0 90)
			(size 0.59 0.64)
			(layers "F.Cu" "F.Mask" "F.Paste")
			(roundrect_rratio 0.25)
			(net 32 "/USB/VCC_USB")
			(pintype "passive")
		)
		(pad "2" smd roundrect
			(at 0.48 0 90)
			(size 0.59 0.64)
			(layers "F.Cu" "F.Mask" "F.Paste")
			(roundrect_rratio 0.25)
			(net 3 "GND")
			(pintype "passive")
		)
	)
	(footprint "antmicro-footprints:TP_SMD_0.75mm"
		(layer "F.Cu")
		(at 74.9 151.43 180)
		(property "Reference" "TP210"
			(at 3.7 -0.25 180)
			(layer "F.SilkS")
			(effects
				(font
					(size 0.7 0.7)
					(thickness 0.15)
				)
				(justify left bottom)
			)
		)
		(property "Value" "TP_0.75mm_SMD"
			(at 0 1.2 180)
			(layer "F.Fab")
			(effects
				(font
					(size 0.7 0.7)
					(thickness 0.15)
				)
				(justify left bottom)
			)
		)
		(property "Author" "Antmicro"
			(at 0 0 180)
			(unlocked yes)
			(layer "F.Fab")
			(hide yes)
			(effects
				(font
					(size 1 1)
					(thickness 0.15)
				)
			)
		)
		(property "License" "Apache-2.0"
			(at 0 0 180)
			(unlocked yes)
			(layer "F.Fab")
			(hide yes)
			(effects
				(font
					(size 1 1)
					(thickness 0.15)
				)
			)
		)
		(property "MPN" ""
			(at 0 0 180)
			(unlocked yes)
			(layer "F.Fab")
			(hide yes)
			(effects
				(font
					(size 1 1)
					(thickness 0.15)
				)
			)
		)
		(property "Manufacturer" ""
			(at 0 0 180)
			(unlocked yes)
			(layer "F.Fab")
			(hide yes)
			(effects
				(font
					(size 1 1)
					(thickness 0.15)
				)
			)
		)
		(sheetname "/Compute module/")
		(sheetfile "compute-module.kicad_sch")
		(attr exclude_from_pos_files exclude_from_bom)
		(fp_circle
			(center 0 0)
			(end 0.475 0)
			(stroke
				(width 0.05)
				(type default)
			)
			(fill no)
			(layer "F.CrtYd")
		)
		(fp_text user "${REFERENCE}"
			(at -0.4 2.7 180)
			(layer "F.Fab")
			(effects
				(font
					(size 0.7 0.7)
					(thickness 0.15)
				)
				(justify left bottom)
			)
		)
		(fp_text user "License: Apache-2.0"
			(at -0.4 5.101 180)
			(layer "F.Fab")
			(effects
				(font
					(size 0.7 0.7)
					(thickness 0.15)
				)
				(justify left bottom)
			)
		)
		(fp_text user "Author: Antmicro"
			(at -0.4 3.901 180)
			(layer "F.Fab")
			(effects
				(font
					(size 0.7 0.7)
					(thickness 0.15)
				)
				(justify left bottom)
			)
		)
		(pad "1" smd circle
			(at 0 0 180)
			(size 0.75 0.75)
			(layers "F.Cu" "F.Mask")
			(net 22 "+1V8")
			(pinfunction "1")
			(pintype "passive")
		)
	)
)
